(kicad_pcb
	(version 20260206)
	(generator "pcbnew")
	(generator_version "10.0")
	(general
		(thickness 1.6)
		(legacy_teardrops no)
	)
	(paper "A4")
	(title_block
		(title "Bryce Canyon_IOM_IOC_16318-2_OCP.brd")
		(comment 1 "Bryce Canyon / footprints 1056-1063 of 1605")
	)
	(layers
		(0 "F.Cu" signal "TOP")
		(4 "In1.Cu" signal "L2GND")
		(6 "In2.Cu" signal "L3")
		(8 "In3.Cu" signal "L4VCC")
		(10 "In4.Cu" signal "L5VCC")
		(12 "In5.Cu" signal "L6")
		(14 "In6.Cu" signal "L7GND")
		(2 "B.Cu" signal "BOTTOM")
		(9 "F.Adhes" user "F.Adhesive")
		(11 "B.Adhes" user "B.Adhesive")
		(13 "F.Paste" user "Package Geometry/Pastemask Top")
		(15 "B.Paste" user "Package Geometry/Pastemask Bottom")
		(5 "F.SilkS" user "Ref Des/Silkscreen Top")
		(7 "B.SilkS" user "Ref Des/Silkscreen Bottom")
		(1 "F.Mask" user "Board Geometry/Soldermask Top")
		(3 "B.Mask" user "Board Geometry/Soldermask Bottom")
		(17 "Dwgs.User" user "User.Drawings")
		(19 "Cmts.User" user "User.Comments")
		(21 "Eco1.User" user "User.Eco1")
		(23 "Eco2.User" user "User.Eco2")
		(25 "Edge.Cuts" user "Board Geometry/Outline")
		(27 "Margin" user)
		(31 "F.CrtYd" user "Package Geometry/Place Bound Top")
		(29 "B.CrtYd" user "Package Geometry/Place Bound Bottom")
		(35 "F.Fab" user "Ref Des/Assembly Top")
		(33 "B.Fab" user "Ref Des/Assembly Bottom")
	)
	(footprint ""
		(layer "B.Cu")
		(at 54.23408 -124.7394 90)
		(property "Reference" "R702"
			(at 0 0 90)
			(layer "B.SilkS")
			(hide yes)
			(effects
				(font
					(size 1.27 1.27)
				)
				(justify mirror)
			)
		)
		(property "Value" "4K7R2F-GP"
			(at -0.064008 -3.993896 90)
			(unlocked yes)
			(layer "B.Fab")
			(hide yes)
			(effects
				(font
					(size 1.016 1.016)
					(thickness 0.1524)
				)
				(justify mirror)
			)
		)
		(property "Device Type" "R402H16"
			(at -0.064008 -5.517896 90)
			(unlocked yes)
			(layer "B.Fab")
			(hide yes)
			(effects
				(font
					(size 1.016 1.016)
					(thickness 0.1524)
				)
				(justify mirror)
			)
		)
		(duplicate_pad_numbers_are_jumpers no)
		(fp_line
			(start 0.508 -0.9398)
			(end 0.508 0.9398)
			(stroke
				(width 0.1524)
				(type default)
			)
			(layer "B.SilkS")
		)
		(fp_line
			(start -0.508 -0.9398)
			(end 0.508 -0.9398)
			(stroke
				(width 0.1524)
				(type default)
			)
			(layer "B.SilkS")
		)
		(fp_rect
			(start 0.508 0.9398)
			(end -0.508 -0.9398)
			(stroke
				(width 0)
				(type default)
			)
			(fill no)
			(layer "B.CrtYd")
		)
		(fp_rect
			(start 0.508 0.9398)
			(end -0.508 -0.9398)
			(stroke
				(width 0)
				(type default)
			)
			(fill no)
			(layer "B.Fab")
		)
		(pad "1" smd custom
			(at 0 -0.4445 270)
			(size 0.1397 0.1397)
			(layers "B.Cu" "B.Mask" "B.Paste")
			(net "P3V3_STBY")
			(options
				(clearance outline)
				(anchor circle)
			)
			(primitives
				(gr_poly
					(pts
						(arc
							(start -0.1778 0.2794)
							(mid -0.249642 0.249642)
							(end -0.2794 0.1778)
						)
						(arc
							(start -0.2794 -0.1778)
							(mid -0.249642 -0.249642)
							(end -0.1778 -0.2794)
						)
						(arc
							(start 0.1778 -0.2794)
							(mid 0.249642 -0.249642)
							(end 0.2794 -0.1778)
						)
						(arc
							(start 0.2794 0.1778)
							(mid 0.249642 0.249642)
							(end 0.1778 0.2794)
						)
					)
					(width 0)
					(fill yes)
				)
			)
		)
		(pad "2" smd custom
			(at 0 0.4445 270)
			(size 0.1397 0.1397)
			(layers "B.Cu" "B.Mask" "B.Paste")
			(net "DEBUG_RST_BTN_N_R")
			(options
				(clearance outline)
				(anchor circle)
			)
			(primitives
				(gr_poly
					(pts
						(arc
							(start -0.1778 0.2794)
							(mid -0.249642 0.249642)
							(end -0.2794 0.1778)
						)
						(arc
							(start -0.2794 -0.1778)
							(mid -0.249642 -0.249642)
							(end -0.1778 -0.2794)
						)
						(arc
							(start 0.1778 -0.2794)
							(mid 0.249642 -0.249642)
							(end 0.2794 -0.1778)
						)
						(arc
							(start 0.2794 0.1778)
							(mid 0.249642 0.249642)
							(end 0.1778 0.2794)
						)
					)
					(width 0)
					(fill yes)
				)
			)
		)
	)
	(footprint ""
		(layer "B.Cu")
		(at 30.38602 -126.8857 -90)
		(property "Reference" "R732"
			(at 0 0 90)
			(layer "B.SilkS")
			(hide yes)
			(effects
				(font
					(size 1.27 1.27)
				)
				(justify mirror)
			)
		)
		(property "Value" "0R2J-2-GP"
			(at -0.064008 -3.993896 270)
			(unlocked yes)
			(layer "B.Fab")
			(hide yes)
			(effects
				(font
					(size 1.016 1.016)
					(thickness 0.1524)
				)
				(justify mirror)
			)
		)
		(property "Device Type" "R402H16"
			(at -0.064008 -5.517896 270)
			(unlocked yes)
			(layer "B.Fab")
			(hide yes)
			(effects
				(font
					(size 1.016 1.016)
					(thickness 0.1524)
				)
				(justify mirror)
			)
		)
		(duplicate_pad_numbers_are_jumpers no)
		(fp_line
			(start -0.508 -0.9398)
			(end 0.508 -0.9398)
			(stroke
				(width 0.1524)
				(type default)
			)
			(layer "B.SilkS")
		)
		(fp_line
			(start 0.508 -0.9398)
			(end 0.508 0.9398)
			(stroke
				(width 0.1524)
				(type default)
			)
			(layer "B.SilkS")
		)
		(fp_rect
			(start 0.508 0.9398)
			(end -0.508 -0.9398)
			(stroke
				(width 0)
				(type default)
			)
			(fill no)
			(layer "B.CrtYd")
		)
		(fp_rect
			(start 0.508 0.9398)
			(end -0.508 -0.9398)
			(stroke
				(width 0)
				(type default)
			)
			(fill no)
			(layer "B.Fab")
		)
		(pad "1" smd custom
			(at 0 -0.4445 90)
			(size 0.1397 0.1397)
			(layers "B.Cu" "B.Mask" "B.Paste")
			(net "U104_EN")
			(options
				(clearance outline)
				(anchor circle)
			)
			(primitives
				(gr_poly
					(pts
						(arc
							(start -0.1778 0.2794)
							(mid -0.249642 0.249642)
							(end -0.2794 0.1778)
						)
						(arc
							(start -0.2794 -0.1778)
							(mid -0.249642 -0.249642)
							(end -0.1778 -0.2794)
						)
						(arc
							(start 0.1778 -0.2794)
							(mid 0.249642 -0.249642)
							(end 0.2794 -0.1778)
						)
						(arc
							(start 0.2794 0.1778)
							(mid 0.249642 0.249642)
							(end 0.1778 0.2794)
						)
					)
					(width 0)
					(fill yes)
				)
			)
		)
		(pad "2" smd custom
			(at 0 0.4445 90)
			(size 0.1397 0.1397)
			(layers "B.Cu" "B.Mask" "B.Paste")
			(net "COMP_PWR_EN")
			(options
				(clearance outline)
				(anchor circle)
			)
			(primitives
				(gr_poly
					(pts
						(arc
							(start -0.1778 0.2794)
							(mid -0.249642 0.249642)
							(end -0.2794 0.1778)
						)
						(arc
							(start -0.2794 -0.1778)
							(mid -0.249642 -0.249642)
							(end -0.1778 -0.2794)
						)
						(arc
							(start 0.1778 -0.2794)
							(mid 0.249642 -0.249642)
							(end 0.2794 -0.1778)
						)
						(arc
							(start 0.2794 0.1778)
							(mid 0.249642 0.249642)
							(end 0.1778 0.2794)
						)
					)
					(width 0)
					(fill yes)
				)
			)
		)
	)
	(footprint ""
		(layer "B.Cu")
		(at 211.836 -84.455 90)
		(property "Reference" "C350"
			(at 0 0 90)
			(layer "B.SilkS")
			(hide yes)
			(effects
				(font
					(size 1.27 1.27)
				)
				(justify mirror)
			)
		)
		(property "Value" "SC22U6D3V3MX-9-GP-U"
			(at 0 -2.8194 90)
			(unlocked yes)
			(layer "B.Fab")
			(hide yes)
			(effects
				(font
					(size 1.016 1.016)
					(thickness 0.1524)
				)
				(justify mirror)
			)
		)
		(property "Device Type" "C603H40"
			(at 0 -4.3434 90)
			(unlocked yes)
			(layer "B.Fab")
			(hide yes)
			(effects
				(font
					(size 1.016 1.016)
					(thickness 0.1524)
				)
				(justify mirror)
			)
		)
		(duplicate_pad_numbers_are_jumpers no)
		(fp_line
			(start -0.508 0)
			(end 0.508 0)
			(stroke
				(width 0.2032)
				(type default)
			)
			(layer "B.SilkS")
		)
		(fp_rect
			(start 0.5842 1.3335)
			(end -0.5842 -1.3335)
			(stroke
				(width 0)
				(type default)
			)
			(fill no)
			(layer "B.CrtYd")
		)
		(fp_rect
			(start 0.5842 1.3335)
			(end -0.5842 -1.3335)
			(stroke
				(width 0)
				(type default)
			)
			(fill no)
			(layer "B.Fab")
		)
		(pad "1" smd custom
			(at 0 -0.762 270)
			(size 0.2159 0.2159)
			(layers "B.Cu" "B.Mask" "B.Paste")
			(net "SAS0_VDDH")
			(options
				(clearance outline)
				(anchor circle)
			)
			(primitives
				(gr_poly
					(pts
						(arc
							(start -0.3302 0.4318)
							(mid -0.402042 0.402042)
							(end -0.4318 0.3302)
						)
						(arc
							(start -0.4318 -0.3302)
							(mid -0.402042 -0.402042)
							(end -0.3302 -0.4318)
						)
						(arc
							(start 0.3302 -0.4318)
							(mid 0.402042 -0.402042)
							(end 0.4318 -0.3302)
						)
						(arc
							(start 0.4318 0.3302)
							(mid 0.402042 0.402042)
							(end 0.3302 0.4318)
						)
					)
					(width 0)
					(fill yes)
				)
			)
		)
		(pad "2" smd custom
			(at 0 0.762 270)
			(size 0.2159 0.2159)
			(layers "B.Cu" "B.Mask" "B.Paste")
			(net "GND")
			(options
				(clearance outline)
				(anchor circle)
			)
			(primitives
				(gr_poly
					(pts
						(arc
							(start -0.3302 0.4318)
							(mid -0.402042 0.402042)
							(end -0.4318 0.3302)
						)
						(arc
							(start -0.4318 -0.3302)
							(mid -0.402042 -0.402042)
							(end -0.3302 -0.4318)
						)
						(arc
							(start 0.3302 -0.4318)
							(mid 0.402042 -0.402042)
							(end 0.4318 -0.3302)
						)
						(arc
							(start 0.4318 0.3302)
							(mid 0.402042 0.402042)
							(end 0.3302 0.4318)
						)
					)
					(width 0)
					(fill yes)
				)
			)
		)
	)
	(footprint ""
		(layer "B.Cu")
		(at 198.530718 -81.153 180)
		(property "Reference" "C294"
			(at 0 0 0)
			(layer "B.SilkS")
			(hide yes)
			(effects
				(font
					(size 1.27 1.27)
				)
				(justify mirror)
			)
		)
		(property "Value" "SCD22U10V1KX-GP"
			(at 2.8321 -1.7399 180)
			(unlocked yes)
			(layer "B.Fab")
			(hide yes)
			(effects
				(font
					(size 1.016 1.016)
					(thickness 0.1524)
				)
				(justify mirror)
			)
		)
		(property "Device Type" "C0201H13"
			(at 2.8321 -3.2639 180)
			(unlocked yes)
			(layer "B.Fab")
			(hide yes)
			(effects
				(font
					(size 1.016 1.016)
					(thickness 0.1524)
				)
				(justify mirror)
			)
		)
		(duplicate_pad_numbers_are_jumpers no)
		(fp_rect
			(start 0.2794 0.6477)
			(end -0.2794 -0.6477)
			(stroke
				(width 0)
				(type default)
			)
			(fill no)
			(layer "B.CrtYd")
		)
		(fp_rect
			(start 0.2794 0.6477)
			(end -0.2794 -0.6477)
			(stroke
				(width 0)
				(type default)
			)
			(fill no)
			(layer "B.Fab")
		)
		(pad "1" smd custom
			(at 0 -0.2794)
			(size 0.0762 0.0762)
			(layers "B.Cu" "B.Mask" "B.Paste")
			(net "PCIE_IOM_TO_COMP_10_DN_C")
			(options
				(clearance outline)
				(anchor circle)
			)
			(primitives
				(gr_poly
					(pts
						(arc
							(start 0.1524 0.127)
							(mid 0.137521 0.162921)
							(end 0.1016 0.1778)
						)
						(arc
							(start -0.1016 0.1778)
							(mid -0.137521 0.162921)
							(end -0.1524 0.127)
						)
						(arc
							(start -0.1524 -0.127)
							(mid -0.137521 -0.162921)
							(end -0.1016 -0.1778)
						)
						(arc
							(start 0.1016 -0.1778)
							(mid 0.137521 -0.162921)
							(end 0.1524 -0.127)
						)
					)
					(width 0)
					(fill yes)
				)
			)
		)
		(pad "2" smd custom
			(at 0 0.2794)
			(size 0.0762 0.0762)
			(layers "B.Cu" "B.Mask" "B.Paste")
			(net "PCIE_IOM_TO_COMP_10_DN")
			(options
				(clearance outline)
				(anchor circle)
			)
			(primitives
				(gr_poly
					(pts
						(arc
							(start 0.1524 0.127)
							(mid 0.137521 0.162921)
							(end 0.1016 0.1778)
						)
						(arc
							(start -0.1016 0.1778)
							(mid -0.137521 0.162921)
							(end -0.1524 0.127)
						)
						(arc
							(start -0.1524 -0.127)
							(mid -0.137521 -0.162921)
							(end -0.1016 -0.1778)
						)
						(arc
							(start 0.1016 -0.1778)
							(mid 0.137521 -0.162921)
							(end 0.1524 -0.127)
						)
					)
					(width 0)
					(fill yes)
				)
			)
		)
	)
	(footprint ""
		(layer "B.Cu")
		(at 50.40884 -152.23236 -90)
		(property "Reference" "R366"
			(at 0 0 90)
			(layer "B.SilkS")
			(hide yes)
			(effects
				(font
					(size 1.27 1.27)
				)
				(justify mirror)
			)
		)
		(property "Value" "49K9R2F-L-GP"
			(at -0.064008 -3.993896 270)
			(unlocked yes)
			(layer "B.Fab")
			(hide yes)
			(effects
				(font
					(size 1.016 1.016)
					(thickness 0.1524)
				)
				(justify mirror)
			)
		)
		(property "Device Type" "R402H16"
			(at -0.064008 -5.517896 270)
			(unlocked yes)
			(layer "B.Fab")
			(hide yes)
			(effects
				(font
					(size 1.016 1.016)
					(thickness 0.1524)
				)
				(justify mirror)
			)
		)
		(duplicate_pad_numbers_are_jumpers no)
		(fp_line
			(start -0.508 -0.9398)
			(end 0.508 -0.9398)
			(stroke
				(width 0.1524)
				(type default)
			)
			(layer "B.SilkS")
		)
		(fp_line
			(start 0.508 -0.9398)
			(end 0.508 0.9398)
			(stroke
				(width 0.1524)
				(type default)
			)
			(layer "B.SilkS")
		)
		(fp_rect
			(start 0.508 0.9398)
			(end -0.508 -0.9398)
			(stroke
				(width 0)
				(type default)
			)
			(fill no)
			(layer "B.CrtYd")
		)
		(fp_rect
			(start 0.508 0.9398)
			(end -0.508 -0.9398)
			(stroke
				(width 0)
				(type default)
			)
			(fill no)
			(layer "B.Fab")
		)
		(pad "1" smd custom
			(at 0 -0.4445 90)
			(size 0.1397 0.1397)
			(layers "B.Cu" "B.Mask" "B.Paste")
			(net "GND")
			(options
				(clearance outline)
				(anchor circle)
			)
			(primitives
				(gr_poly
					(pts
						(arc
							(start -0.1778 0.2794)
							(mid -0.249642 0.249642)
							(end -0.2794 0.1778)
						)
						(arc
							(start -0.2794 -0.1778)
							(mid -0.249642 -0.249642)
							(end -0.1778 -0.2794)
						)
						(arc
							(start 0.1778 -0.2794)
							(mid 0.249642 -0.249642)
							(end 0.2794 -0.1778)
						)
						(arc
							(start 0.2794 0.1778)
							(mid 0.249642 0.249642)
							(end 0.1778 0.2794)
						)
					)
					(width 0)
					(fill yes)
				)
			)
		)
		(pad "2" smd custom
			(at 0 0.4445 90)
			(size 0.1397 0.1397)
			(layers "B.Cu" "B.Mask" "B.Paste")
			(net "ADCVREXT")
			(options
				(clearance outline)
				(anchor circle)
			)
			(primitives
				(gr_poly
					(pts
						(arc
							(start -0.1778 0.2794)
							(mid -0.249642 0.249642)
							(end -0.2794 0.1778)
						)
						(arc
							(start -0.2794 -0.1778)
							(mid -0.249642 -0.249642)
							(end -0.1778 -0.2794)
						)
						(arc
							(start 0.1778 -0.2794)
							(mid 0.249642 -0.249642)
							(end 0.2794 -0.1778)
						)
						(arc
							(start 0.2794 0.1778)
							(mid 0.249642 0.249642)
							(end 0.1778 0.2794)
						)
					)
					(width 0)
					(fill yes)
				)
			)
		)
	)
	(footprint ""
		(layer "B.Cu")
		(at 191.68999 -21.209 -90)
		(property "Reference" "C489"
			(at 0 0 90)
			(layer "B.SilkS")
			(hide yes)
			(effects
				(font
					(size 1.27 1.27)
				)
				(justify mirror)
			)
		)
		(property "Value" "SCD01U16V1KX-GP"
			(at 2.8321 -1.7399 270)
			(unlocked yes)
			(layer "B.Fab")
			(hide yes)
			(effects
				(font
					(size 1.016 1.016)
					(thickness 0.1524)
				)
				(justify mirror)
			)
		)
		(property "Device Type" "C0201H13"
			(at 2.8321 -3.2639 270)
			(unlocked yes)
			(layer "B.Fab")
			(hide yes)
			(effects
				(font
					(size 1.016 1.016)
					(thickness 0.1524)
				)
				(justify mirror)
			)
		)
		(duplicate_pad_numbers_are_jumpers no)
		(fp_rect
			(start 0.2794 0.6477)
			(end -0.2794 -0.6477)
			(stroke
				(width 0)
				(type default)
			)
			(fill no)
			(layer "B.CrtYd")
		)
		(fp_rect
			(start 0.2794 0.6477)
			(end -0.2794 -0.6477)
			(stroke
				(width 0)
				(type default)
			)
			(fill no)
			(layer "B.Fab")
		)
		(pad "1" smd custom
			(at 0 -0.2794 90)
			(size 0.0762 0.0762)
			(layers "B.Cu" "B.Mask" "B.Paste")
			(net "PHY_CON_A_TO_IOC_1_DN")
			(options
				(clearance outline)
				(anchor circle)
			)
			(primitives
				(gr_poly
					(pts
						(arc
							(start 0.1524 0.127)
							(mid 0.137521 0.162921)
							(end 0.1016 0.1778)
						)
						(arc
							(start -0.1016 0.1778)
							(mid -0.137521 0.162921)
							(end -0.1524 0.127)
						)
						(arc
							(start -0.1524 -0.127)
							(mid -0.137521 -0.162921)
							(end -0.1016 -0.1778)
						)
						(arc
							(start 0.1016 -0.1778)
							(mid 0.137521 -0.162921)
							(end 0.1524 -0.127)
						)
					)
					(width 0)
					(fill yes)
				)
			)
		)
		(pad "2" smd custom
			(at 0 0.2794 90)
			(size 0.0762 0.0762)
			(layers "B.Cu" "B.Mask" "B.Paste")
			(net "PHY_CON_A_TO_IOC_1_DN_C")
			(options
				(clearance outline)
				(anchor circle)
			)
			(primitives
				(gr_poly
					(pts
						(arc
							(start 0.1524 0.127)
							(mid 0.137521 0.162921)
							(end 0.1016 0.1778)
						)
						(arc
							(start -0.1016 0.1778)
							(mid -0.137521 0.162921)
							(end -0.1524 0.127)
						)
						(arc
							(start -0.1524 -0.127)
							(mid -0.137521 -0.162921)
							(end -0.1016 -0.1778)
						)
						(arc
							(start 0.1016 -0.1778)
							(mid 0.137521 -0.162921)
							(end 0.1524 -0.127)
						)
					)
					(width 0)
					(fill yes)
				)
			)
		)
	)
	(footprint ""
		(layer "B.Cu")
		(at 209.0674 -57.2516)
		(property "Reference" "TP120"
			(at 0 0 0)
			(layer "B.SilkS")
			(hide yes)
			(effects
				(font
					(size 1.27 1.27)
				)
				(justify mirror)
			)
		)
		(property "Value" "TPAD28-2-GP"
			(at 0.0127 -1.6637 0)
			(unlocked yes)
			(layer "B.Fab")
			(hide yes)
			(effects
				(font
					(size 1.016 1.016)
					(thickness 0.1524)
				)
				(justify mirror)
			)
		)
		(property "Device Type" "TPAD28"
			(at 0.0127 -3.1877 0)
			(unlocked yes)
			(layer "B.Fab")
			(hide yes)
			(effects
				(font
					(size 1.016 1.016)
					(thickness 0.1524)
				)
				(justify mirror)
			)
		)
		(duplicate_pad_numbers_are_jumpers no)
		(fp_poly
			(pts
				(arc
					(start 0.3556 0)
					(mid -0.3556 0)
					(end 0.3556 0)
				)
			)
			(stroke
				(width 0)
				(type default)
			)
			(fill no)
			(layer "B.CrtYd")
		)
		(fp_poly
			(pts
				(arc
					(start 0.6096 0)
					(mid -0.6096 0)
					(end 0.6096 0)
				)
			)
			(stroke
				(width 0)
				(type default)
			)
			(fill no)
			(layer "B.Fab")
		)
		(pad "1" smd circle
			(at 0 0 180)
			(size 0.7112 0.7112)
			(layers "B.Cu" "B.Mask" "B.Paste")
			(net "SIO_CLK_1")
		)
	)
	(footprint ""
		(layer "B.Cu")
		(at 87.8332 -174.625 90)
		(property "Reference" "R418"
			(at 0 0 90)
			(layer "B.SilkS")
			(hide yes)
			(effects
				(font
					(size 1.27 1.27)
				)
				(justify mirror)
			)
		)
		(property "Value" "0R2J-2-GP"
			(at -0.064008 -3.993896 90)
			(unlocked yes)
			(layer "B.Fab")
			(hide yes)
			(effects
				(font
					(size 1.016 1.016)
					(thickness 0.1524)
				)
				(justify mirror)
			)
		)
		(property "Device Type" "R402H16"
			(at -0.064008 -5.517896 90)
			(unlocked yes)
			(layer "B.Fab")
			(hide yes)
			(effects
				(font
					(size 1.016 1.016)
					(thickness 0.1524)
				)
				(justify mirror)
			)
		)
		(duplicate_pad_numbers_are_jumpers no)
		(fp_line
			(start 0.508 -0.9398)
			(end 0.508 0.9398)
			(stroke
				(width 0.1524)
				(type default)
			)
			(layer "B.SilkS")
		)
		(fp_line
			(start -0.508 -0.9398)
			(end 0.508 -0.9398)
			(stroke
				(width 0.1524)
				(type default)
			)
			(layer "B.SilkS")
		)
		(fp_rect
			(start 0.508 0.9398)
			(end -0.508 -0.9398)
			(stroke
				(width 0)
				(type default)
			)
			(fill no)
			(layer "B.CrtYd")
		)
		(fp_rect
			(start 0.508 0.9398)
			(end -0.508 -0.9398)
			(stroke
				(width 0)
				(type default)
			)
			(fill no)
			(layer "B.Fab")
		)
		(pad "1" smd custom
			(at 0 -0.4445 270)
			(size 0.1397 0.1397)
			(layers "B.Cu" "B.Mask" "B.Paste")
			(net "UART_COMP_R_TX")
			(options
				(clearance outline)
				(anchor circle)
			)
			(primitives
				(gr_poly
					(pts
						(arc
							(start -0.1778 0.2794)
							(mid -0.249642 0.249642)
							(end -0.2794 0.1778)
						)
						(arc
							(start -0.2794 -0.1778)
							(mid -0.249642 -0.249642)
							(end -0.1778 -0.2794)
						)
						(arc
							(start 0.1778 -0.2794)
							(mid 0.249642 -0.249642)
							(end 0.2794 -0.1778)
						)
						(arc
							(start 0.2794 0.1778)
							(mid 0.249642 0.249642)
							(end 0.1778 0.2794)
						)
					)
					(width 0)
					(fill yes)
				)
			)
		)
		(pad "2" smd custom
			(at 0 0.4445 270)
			(size 0.1397 0.1397)
			(layers "B.Cu" "B.Mask" "B.Paste")
			(net "UART_COMP_TX")
			(options
				(clearance outline)
				(anchor circle)
			)
			(primitives
				(gr_poly
					(pts
						(arc
							(start -0.1778 0.2794)
							(mid -0.249642 0.249642)
							(end -0.2794 0.1778)
						)
						(arc
							(start -0.2794 -0.1778)
							(mid -0.249642 -0.249642)
							(end -0.1778 -0.2794)
						)
						(arc
							(start 0.1778 -0.2794)
							(mid 0.249642 -0.249642)
							(end 0.2794 -0.1778)
						)
						(arc
							(start 0.2794 0.1778)
							(mid 0.249642 0.249642)
							(end 0.1778 0.2794)
						)
					)
					(width 0)
					(fill yes)
				)
			)
		)
	)
)
